# T6G (Grand Teton) — schematic netlist excerpt (pin names and nets, part order shuffled) for the footprints in the layout excerpt that follows; sources: Cadence DE-HDL packaged netlist, KiCad conversion of 04192023_DAF0TMB3IC0_F0TG_MB_C_brd_V02_OCP.brd

R2703  Q_RES  0 5% CHIP  pkg 0402LF  page 250 : A = SMB_BMC_SWB_SCL_R4 ; B = SMB_BMC_SWB_SCL
C684  Q_CAP_DIFFBUS  DIFF BUS_0.22UF 6.3V 20% X6S  pkg C0201  page 67 : \1\ = P5E_CPU1_G1_TX_C_DN<12> ; \2\ = P5E_CPU1_G1_TX_DN<12>
C6566  Q_CAP_DIFFBUS  DIFF BUS_0.22UF 6.3V 20% X6S  pkg C0201  page 297 : \1\ = P5E_CPU0_P2_TX_BUF_C_DN<0> ; \2\ = P5E_CPU0_P2_TX_BUF_DN<0>

(kicad_pcb
	(version 20260206)
	(generator "pcbnew")
	(generator_version "10.0")
	(general
		(thickness 1.6)
		(legacy_teardrops no)
	)
	(paper "A4")
	(title_block
		(title "04192023_DAF0TMB3IC0_F0TG_MB_C_brd_V02_OCP.brd")
		(comment 1 "Grand Teton / footprints 1185-1187 of 8354")
	)
	(layers
		(0 "F.Cu" signal "TOP")
		(4 "In1.Cu" signal "GND")
		(6 "In2.Cu" signal "IN1")
		(8 "In3.Cu" signal "GND1")
		(10 "In4.Cu" signal "IN2")
		(12 "In5.Cu" signal "GND2")
		(14 "In6.Cu" signal "IN3")
		(16 "In7.Cu" signal "GND3")
		(18 "In8.Cu" signal "VCC")
		(20 "In9.Cu" signal "VCC1")
		(22 "In10.Cu" signal "GND4")
		(24 "In11.Cu" signal "IN4")
		(26 "In12.Cu" signal "GND5")
		(28 "In13.Cu" signal "IN5")
		(30 "In14.Cu" signal "GND6")
		(32 "In15.Cu" signal "IN6")
		(34 "In16.Cu" signal "GND7")
		(2 "B.Cu" signal "BOTTOM")
		(9 "F.Adhes" user "F.Adhesive")
		(11 "B.Adhes" user "B.Adhesive")
		(13 "F.Paste" user "Package Geometry/Pastemask Top")
		(15 "B.Paste" user "Package Geometry/Pastemask Bottom")
		(5 "F.SilkS" user "Ref Des/Silkscreen Top")
		(7 "B.SilkS" user "Ref Des/Silkscreen Bottom")
		(1 "F.Mask" user "Board Geometry/Soldermask Top")
		(3 "B.Mask" user "Board Geometry/Soldermask Bottom")
		(17 "Dwgs.User" user "User.Drawings")
		(19 "Cmts.User" user "User.Comments")
		(21 "Eco1.User" user "User.Eco1")
		(23 "Eco2.User" user "User.Eco2")
		(25 "Edge.Cuts" user "Board Geometry/Outline")
		(27 "Margin" user)
		(31 "F.CrtYd" user "Package Geometry/Place Bound Top")
		(29 "B.CrtYd" user "Package Geometry/Place Bound Bottom")
		(35 "F.Fab" user "Ref Des/Assembly Top")
		(33 "B.Fab" user "Ref Des/Assembly Bottom")
	)
	(footprint ""
		(layer "F.Cu")
		(at 294.421052 -115.237514)
		(property "Reference" "R2703"
			(at 0 0 0)
			(layer "F.SilkS")
			(hide yes)
			(effects
				(font
					(size 1.27 1.27)
				)
			)
		)
		(property "Value" ""
			(at 0 0 0)
			(layer "F.Fab")
			(effects
				(font
					(size 1.27 1.27)
				)
			)
		)
		(duplicate_pad_numbers_are_jumpers no)
		(fp_line
			(start -0.7874 -0.4064)
			(end 0.7874 -0.4064)
			(stroke
				(width 0.1524)
				(type default)
			)
			(layer "F.SilkS")
		)
		(fp_line
			(start -0.7874 0.4064)
			(end -0.7874 -0.4064)
			(stroke
				(width 0.1524)
				(type default)
			)
			(layer "F.SilkS")
		)
		(fp_line
			(start 0.7874 -0.4064)
			(end 0.7874 0.4064)
			(stroke
				(width 0.1524)
				(type default)
			)
			(layer "F.SilkS")
		)
		(fp_line
			(start 0.7874 0.4064)
			(end -0.7874 0.4064)
			(stroke
				(width 0.1524)
				(type default)
			)
			(layer "F.SilkS")
		)
		(fp_line
			(start -0.67945 -0.305054)
			(end -0.12065 -0.305054)
			(stroke
				(width 0.1)
				(type default)
			)
			(layer "F.Fab")
		)
		(fp_line
			(start -0.67945 0.3048)
			(end -0.67945 -0.305054)
			(stroke
				(width 0.1)
				(type default)
			)
			(layer "F.Fab")
		)
		(fp_line
			(start -0.12065 -0.305054)
			(end -0.12065 -0.2794)
			(stroke
				(width 0.1)
				(type default)
			)
			(layer "F.Fab")
		)
		(fp_line
			(start -0.12065 -0.2794)
			(end 0.12065 -0.2794)
			(stroke
				(width 0.1)
				(type default)
			)
			(layer "F.Fab")
		)
		(fp_line
			(start -0.12065 0.2794)
			(end -0.12065 0.3048)
			(stroke
				(width 0.1)
				(type default)
			)
			(layer "F.Fab")
		)
		(fp_line
			(start -0.12065 0.3048)
			(end -0.67945 0.3048)
			(stroke
				(width 0.1)
				(type default)
			)
			(layer "F.Fab")
		)
		(fp_line
			(start 0.120396 0.2794)
			(end -0.12065 0.2794)
			(stroke
				(width 0.1)
				(type default)
			)
			(layer "F.Fab")
		)
		(fp_line
			(start 0.120396 0.3048)
			(end 0.120396 0.2794)
			(stroke
				(width 0.1)
				(type default)
			)
			(layer "F.Fab")
		)
		(fp_line
			(start 0.12065 -0.3048)
			(end 0.67945 -0.3048)
			(stroke
				(width 0.1)
				(type default)
			)
			(layer "F.Fab")
		)
		(fp_line
			(start 0.12065 -0.2794)
			(end 0.12065 -0.3048)
			(stroke
				(width 0.1)
				(type default)
			)
			(layer "F.Fab")
		)
		(fp_line
			(start 0.67945 -0.3048)
			(end 0.67945 0.3048)
			(stroke
				(width 0.1)
				(type default)
			)
			(layer "F.Fab")
		)
		(fp_line
			(start 0.67945 0.3048)
			(end 0.120396 0.3048)
			(stroke
				(width 0.1)
				(type default)
			)
			(layer "F.Fab")
		)
		(pad "1" smd circle
			(at -0.40005 0)
			(size 0 0)
			(layers "F.Cu" "F.Mask" "F.Paste")
			(net "SMB_BMC_SWB_SCL_R4")
		)
		(pad "2" smd circle
			(at 0.40005 0)
			(size 0 0)
			(layers "F.Cu" "F.Mask" "F.Paste")
			(net "SMB_BMC_SWB_SCL")
		)
	)
	(footprint ""
		(layer "F.Cu")
		(at 370.767102 -414.636458 -90)
		(property "Reference" "C6566"
			(at 0 0 270)
			(layer "F.SilkS")
			(hide yes)
			(effects
				(font
					(size 1.27 1.27)
				)
			)
		)
		(property "Value" ""
			(at 0 0 270)
			(layer "F.Fab")
			(effects
				(font
					(size 1.27 1.27)
				)
			)
		)
		(duplicate_pad_numbers_are_jumpers no)
		(fp_line
			(start -0.299974 0.150114)
			(end -0.299974 -0.150114)
			(stroke
				(width 0.1)
				(type default)
			)
			(layer "F.Fab")
		)
		(fp_line
			(start 0.299974 0.150114)
			(end -0.299974 0.150114)
			(stroke
				(width 0.1)
				(type default)
			)
			(layer "F.Fab")
		)
		(fp_line
			(start -0.299974 -0.150114)
			(end 0.299974 -0.150114)
			(stroke
				(width 0.1)
				(type default)
			)
			(layer "F.Fab")
		)
		(fp_line
			(start 0.299974 -0.150114)
			(end 0.299974 0.150114)
			(stroke
				(width 0.1)
				(type default)
			)
			(layer "F.Fab")
		)
		(pad "1" smd rect
			(at -0.2667 0 270)
			(size 0.3048 0.381)
			(layers "F.Cu" "F.Mask" "F.Paste")
			(net "P5E_CPU0_P2_TX_BUF_C_DN<0>")
		)
		(pad "2" smd rect
			(at 0.2667 0 270)
			(size 0.3048 0.381)
			(layers "F.Cu" "F.Mask" "F.Paste")
			(net "P5E_CPU0_P2_TX_BUF_DN<0>")
		)
	)
	(footprint ""
		(layer "F.Cu")
		(at 23.890478 -17.623536 90)
		(property "Reference" "C684"
			(at 0 0 90)
			(layer "F.SilkS")
			(hide yes)
			(effects
				(font
					(size 1.27 1.27)
				)
			)
		)
		(property "Value" ""
			(at 0 0 90)
			(layer "F.Fab")
			(effects
				(font
					(size 1.27 1.27)
				)
			)
		)
		(duplicate_pad_numbers_are_jumpers no)
		(fp_line
			(start 0.299974 -0.150114)
			(end 0.299974 0.150114)
			(stroke
				(width 0.1)
				(type default)
			)
			(layer "F.Fab")
		)
		(fp_line
			(start -0.299974 -0.150114)
			(end 0.299974 -0.150114)
			(stroke
				(width 0.1)
				(type default)
			)
			(layer "F.Fab")
		)
		(fp_line
			(start 0.299974 0.150114)
			(end -0.299974 0.150114)
			(stroke
				(width 0.1)
				(type default)
			)
			(layer "F.Fab")
		)
		(fp_line
			(start -0.299974 0.150114)
			(end -0.299974 -0.150114)
			(stroke
				(width 0.1)
				(type default)
			)
			(layer "F.Fab")
		)
		(pad "1" smd rect
			(at -0.2667 0 90)
			(size 0.3048 0.381)
			(layers "F.Cu" "F.Mask" "F.Paste")
			(net "P5E_CPU1_G1_TX_C_DN<12>")
		)
		(pad "2" smd rect
			(at 0.2667 0 90)
			(size 0.3048 0.381)
			(layers "F.Cu" "F.Mask" "F.Paste")
			(net "P5E_CPU1_G1_TX_DN<12>")
		)
	)
)
